(kicad_pcb
	(version 20260206)
	(generator "pcbnew")
	(generator_version "10.0")
	(general
		(thickness 1.21888)
		(legacy_teardrops no)
	)
	(paper "A4")
	(title_block
		(title "timecard-v8 — TimeCard-DC-V8_EXP.PcbDoc")
		(comment 1 "Time Appliance Project (Time Card) / footprints 144-149 of 288")
	)
	(layers
		(0 "F.Cu" signal "TOP")
		(4 "In1.Cu" signal "SGND")
		(6 "In2.Cu" signal "IN1")
		(8 "In3.Cu" signal "IN2")
		(10 "In4.Cu" signal "SGND1")
		(2 "B.Cu" signal "BOTTOM")
		(9 "F.Adhes" user "F.Adhesive")
		(11 "B.Adhes" user "B.Adhesive")
		(13 "F.Paste" user "Top Paste")
		(15 "B.Paste" user "Bottom Paste")
		(5 "F.SilkS" user "Top Overlay")
		(7 "B.SilkS" user "Bottom Overlay")
		(1 "F.Mask" user "Top Solder")
		(3 "B.Mask" user "Bottom Solder")
		(17 "Dwgs.User" user "User.Drawings")
		(19 "Cmts.User" user "User.Comments")
		(21 "Eco1.User" user "User.Eco1")
		(23 "Eco2.User" user "User.Eco2")
		(25 "Edge.Cuts" user)
		(27 "Margin" user)
		(31 "F.CrtYd" user "Top Courtyard")
		(29 "B.CrtYd" user "Bottom Courtyard")
		(35 "F.Fab" user "Top Component Center")
		(33 "B.Fab" user "Bottom Component Center")
	)
	(footprint "Vault:FP-ERJ2RK-IPC_A"
		(layer "F.Cu")
		(at 174.0261 85.31405 -90)
		(property "Reference" "R94"
			(at 0.33075 -1.573069 270)
			(unlocked yes)
			(layer "F.SilkS")
			(effects
				(font
					(size 0.762 0.762)
					(thickness 0.2286)
				)
			)
		)
		(property "Value" "200_1%_0402"
			(at -2.935471 7.782475 180)
			(unlocked yes)
			(layer "F.SilkS")
			(hide yes)
			(effects
				(font
					(size 0.762 0.762)
					(thickness 0.2286)
				)
			)
		)
		(sheetname "USBUart_DipSelects")
		(sheetfile "USBUart_DipSelects.kicad_sch")
		(duplicate_pad_numbers_are_jumpers no)
		(fp_line
			(start 0.83624 0.73624)
			(end -0.83623 0.73624)
			(stroke
				(width 0.2)
				(type solid)
			)
			(layer "F.SilkS")
		)
		(fp_line
			(start 0.83624 -0.73624)
			(end -0.83623 -0.73624)
			(stroke
				(width 0.2)
				(type solid)
			)
			(layer "F.SilkS")
		)
		(fp_line
			(start -1.03623 0.53624)
			(end -1.03623 -0.53624)
			(stroke
				(width 0.2)
				(type solid)
			)
			(layer "F.CrtYd")
		)
		(fp_line
			(start 1.03624 0.53624)
			(end -1.03623 0.53624)
			(stroke
				(width 0.2)
				(type solid)
			)
			(layer "F.CrtYd")
		)
		(fp_line
			(start 1.03624 0.53624)
			(end 1.03624 -0.53624)
			(stroke
				(width 0.2)
				(type solid)
			)
			(layer "F.CrtYd")
		)
		(fp_line
			(start 1.03624 -0.53624)
			(end -1.03623 -0.53624)
			(stroke
				(width 0.2)
				(type solid)
			)
			(layer "F.CrtYd")
		)
		(fp_line
			(start -1.03623 0.53624)
			(end -1.03623 -0.53624)
			(stroke
				(width 0.2)
				(type solid)
			)
			(layer "F.Fab")
		)
		(fp_line
			(start 1.03624 0.53624)
			(end -1.03623 0.53624)
			(stroke
				(width 0.2)
				(type solid)
			)
			(layer "F.Fab")
		)
		(fp_line
			(start 1.03624 0.53624)
			(end 1.03624 -0.53624)
			(stroke
				(width 0.2)
				(type solid)
			)
			(layer "F.Fab")
		)
		(fp_line
			(start 0 0.5)
			(end 0 -0.5)
			(stroke
				(width 0.1)
				(type solid)
			)
			(layer "F.Fab")
		)
		(fp_line
			(start 0.5 0)
			(end -0.5 0)
			(stroke
				(width 0.1)
				(type solid)
			)
			(layer "F.Fab")
		)
		(fp_line
			(start 1.03624 -0.53624)
			(end -1.03623 -0.53624)
			(stroke
				(width 0.2)
				(type solid)
			)
			(layer "F.Fab")
		)
		(fp_text user "${REFERENCE}"
			(at -0.00001 0.09602 270)
			(unlocked yes)
			(layer "F.Fab")
			(effects
				(font
					(face "Arial")
					(size 0.63 0.63)
					(thickness 0.1)
				)
				(justify left bottom)
			)
		)
		(pad "1" smd rect
			(at -0.50214 0 270)
			(size 0.66818 0.67248)
			(layers "F.Cu" "F.Mask" "F.Paste")
			(net "DIP_SW_PPS_SEL")
			(solder_mask_margin 0)
			(solder_paste_margin 0)
		)
		(pad "2" smd rect
			(at 0.50215 0 270)
			(size 0.66818 0.67248)
			(layers "F.Cu" "F.Mask" "F.Paste")
			(net "NetD24_1")
			(solder_mask_margin 0)
			(solder_paste_margin 0)
		)
	)
	(footprint "Passives:SOT65P210X110-3N"
		(layer "F.Cu")
		(at 195.11136 139.37763)
		(property "Reference" "D5"
			(at -3.38526 -0.968085 0)
			(unlocked yes)
			(layer "F.SilkS")
			(effects
				(font
					(size 0.762 0.762)
					(thickness 0.2286)
				)
				(justify left bottom)
			)
		)
		(property "Value" "BAT54SW"
			(at -10.7749 -6.323555 0)
			(unlocked yes)
			(layer "F.SilkS")
			(hide yes)
			(effects
				(font
					(size 0.762 0.762)
					(thickness 0.2286)
				)
				(justify left bottom)
			)
		)
		(sheetname "PCIe_JTAG")
		(sheetfile "PCIe_JTAG.kicad_sch")
		(duplicate_pad_numbers_are_jumpers no)
		(fp_line
			(start -0.325 -1.1)
			(end 0.675 -1.1)
			(stroke
				(width 0.2)
				(type solid)
			)
			(layer "F.SilkS")
		)
		(fp_line
			(start -0.325 1.1)
			(end 0.675 1.1)
			(stroke
				(width 0.2)
				(type solid)
			)
			(layer "F.SilkS")
		)
		(fp_line
			(start 0.675 -0.65)
			(end 0.675 -1.1)
			(stroke
				(width 0.2)
				(type solid)
			)
			(layer "F.SilkS")
		)
		(fp_line
			(start 0.675 1.1)
			(end 0.675 0.65)
			(stroke
				(width 0.2)
				(type solid)
			)
			(layer "F.SilkS")
		)
		(fp_circle
			(center -1.125 -1.45)
			(end -1.125 -1.575)
			(stroke
				(width 0.25)
				(type solid)
			)
			(fill no)
			(layer "F.SilkS")
		)
		(pad "1" smd rect
			(at -1.125 -0.65 90)
			(size 0.5 0.9)
			(layers "F.Cu" "F.Mask" "F.Paste")
			(net "GND")
		)
		(pad "2" smd rect
			(at -1.125 0.65 90)
			(size 0.5 0.9)
			(layers "F.Cu" "F.Mask" "F.Paste")
			(net "+3.3V")
		)
		(pad "3" smd rect
			(at 1.125 0 90)
			(size 0.5 0.9)
			(layers "F.Cu" "F.Mask" "F.Paste")
			(net "FPGA_TCK")
		)
	)
	(footprint "Vault:CAPC1608X87X45ML20T05"
		(layer "F.Cu")
		(at 218.76876 58.67651)
		(property "Reference" "C36"
			(at -2.91406 -0.070979 0)
			(unlocked yes)
			(layer "F.SilkS")
			(effects
				(font
					(size 0.762 0.762)
					(thickness 0.2286)
				)
			)
		)
		(property "Value" "0.1uF"
			(at 2.069035 2.630671 0)
			(unlocked yes)
			(layer "F.SilkS")
			(hide yes)
			(effects
				(font
					(size 0.762 0.762)
					(thickness 0.2286)
				)
			)
		)
		(sheetname "GPS_IMU_SENSORS")
		(sheetfile "GPS_IMU_SENSORS.kicad_sch")
		(duplicate_pad_numbers_are_jumpers no)
		(pad "1" smd rect
			(at -0.7 0 90)
			(size 1.1 1.05)
			(layers "F.Cu" "F.Mask" "F.Paste")
			(net "GND")
		)
		(pad "2" smd rect
			(at 0.7 0 90)
			(size 1.1 1.05)
			(layers "F.Cu" "F.Mask" "F.Paste")
			(net "+3.3V")
		)
	)
	(footprint "Vault:FP-T495D107K016ATE125-MFG"
		(layer "F.Cu")
		(at 206.7261 117.3162)
		(property "Reference" "C75"
			(at 6.589529 0.01204 270)
			(unlocked yes)
			(layer "F.SilkS")
			(effects
				(font
					(size 0.762 0.762)
					(thickness 0.2286)
				)
			)
		)
		(property "Value" "100uF_16V_2917"
			(at -5.818361 8.010455 270)
			(unlocked yes)
			(layer "F.SilkS")
			(hide yes)
			(effects
				(font
					(size 0.762 0.762)
					(thickness 0.2286)
				)
			)
		)
		(sheetname "POWER")
		(sheetfile "POWER.kicad_sch")
		(duplicate_pad_numbers_are_jumpers no)
		(fp_line
			(start -3.8 -2.3)
			(end 3.8 -2.3)
			(stroke
				(width 0.2)
				(type solid)
			)
			(layer "F.SilkS")
		)
		(fp_line
			(start -3.8 -1.54)
			(end -3.8 -2.3)
			(stroke
				(width 0.2)
				(type solid)
			)
			(layer "F.SilkS")
		)
		(fp_line
			(start -3.8 2.3)
			(end -3.8 1.54)
			(stroke
				(width 0.2)
				(type solid)
			)
			(layer "F.SilkS")
		)
		(fp_line
			(start -3.8 2.3)
			(end 3.8 2.3)
			(stroke
				(width 0.2)
				(type solid)
			)
			(layer "F.SilkS")
		)
		(fp_line
			(start 3.8 -1.54)
			(end 3.8 -2.3)
			(stroke
				(width 0.2)
				(type solid)
			)
			(layer "F.SilkS")
		)
		(fp_line
			(start 3.8 2.3)
			(end 3.8 1.54)
			(stroke
				(width 0.2)
				(type solid)
			)
			(layer "F.SilkS")
		)
		(fp_line
			(start 4.4 0)
			(end 5 0)
			(stroke
				(width 0.2)
				(type solid)
			)
			(layer "F.SilkS")
		)
		(fp_line
			(start 4.7 0.3)
			(end 4.7 -0.3)
			(stroke
				(width 0.2)
				(type solid)
			)
			(layer "F.SilkS")
		)
		(fp_line
			(start -4.105 -2.4)
			(end 4.105 -2.4)
			(stroke
				(width 0.2)
				(type solid)
			)
			(layer "F.CrtYd")
		)
		(fp_line
			(start -4.105 2.4)
			(end -4.105 -2.4)
			(stroke
				(width 0.2)
				(type solid)
			)
			(layer "F.CrtYd")
		)
		(fp_line
			(start -4.105 2.4)
			(end 4.105 2.4)
			(stroke
				(width 0.2)
				(type solid)
			)
			(layer "F.CrtYd")
		)
		(fp_line
			(start 4.105 2.4)
			(end 4.105 -2.4)
			(stroke
				(width 0.2)
				(type solid)
			)
			(layer "F.CrtYd")
		)
		(fp_line
			(start -4.105 -2.4)
			(end 4.105 -2.4)
			(stroke
				(width 0.2)
				(type solid)
			)
			(layer "F.Fab")
		)
		(fp_line
			(start -4.105 2.4)
			(end -4.105 -2.4)
			(stroke
				(width 0.2)
				(type solid)
			)
			(layer "F.Fab")
		)
		(fp_line
			(start -4.105 2.4)
			(end 4.105 2.4)
			(stroke
				(width 0.2)
				(type solid)
			)
			(layer "F.Fab")
		)
		(fp_line
			(start -0.5 0)
			(end 0.5 0)
			(stroke
				(width 0.1)
				(type solid)
			)
			(layer "F.Fab")
		)
		(fp_line
			(start 0 0.5)
			(end 0 -0.5)
			(stroke
				(width 0.1)
				(type solid)
			)
			(layer "F.Fab")
		)
		(fp_line
			(start 4.105 2.4)
			(end 4.105 -2.4)
			(stroke
				(width 0.2)
				(type solid)
			)
			(layer "F.Fab")
		)
		(fp_text user "${REFERENCE}"
			(at 0 0.28425 360)
			(unlocked yes)
			(layer "F.Fab")
			(effects
				(font
					(face "Arial")
					(size 0.63 0.63)
					(thickness 0.1)
				)
				(justify left bottom)
			)
		)
		(pad "1" smd rect
			(at -3.01 0)
			(size 1.99 2.33)
			(layers "F.Cu" "F.Mask" "F.Paste")
			(net "GND")
			(solder_mask_margin 0)
			(solder_paste_margin 0)
		)
		(pad "2" smd rect
			(at 3.01 0)
			(size 1.99 2.33)
			(layers "F.Cu" "F.Mask" "F.Paste")
			(net "+12V")
			(solder_mask_margin 0)
			(solder_paste_margin 0)
		)
	)
	(footprint "Vault:FP-2049261103-MFG"
		(layer "F.Cu")
		(at 239.3261 77.7162 90)
		(property "Reference" "J43"
			(at -5.773069 -1.0286 180)
			(unlocked yes)
			(layer "F.SilkS")
			(effects
				(font
					(size 0.762 0.762)
					(thickness 0.2286)
				)
			)
		)
		(property "Value" "2049261103"
			(at 2.6266 5.323071 90)
			(unlocked yes)
			(layer "F.SilkS")
			(hide yes)
			(effects
				(font
					(size 0.762 0.762)
					(thickness 0.2286)
				)
			)
		)
		(sheetname "USBUart_DipSelects")
		(sheetfile "USBUart_DipSelects.kicad_sch")
		(duplicate_pad_numbers_are_jumpers no)
		(fp_line
			(start 4.875 -3.525)
			(end 4.875 -2.475)
			(stroke
				(width 0.2)
				(type solid)
			)
			(layer "F.SilkS")
		)
		(fp_line
			(start 4.575 -3.525)
			(end 4.875 -3.525)
			(stroke
				(width 0.2)
				(type solid)
			)
			(layer "F.SilkS")
		)
		(fp_line
			(start 1.9 -3.525)
			(end 2.625 -3.525)
			(stroke
				(width 0.2)
				(type solid)
			)
			(layer "F.SilkS")
		)
		(fp_line
			(start -2.625 -3.525)
			(end -1.9 -3.525)
			(stroke
				(width 0.2)
				(type solid)
			)
			(layer "F.SilkS")
		)
		(fp_line
			(start -4.875 -3.525)
			(end -4.575 -3.525)
			(stroke
				(width 0.2)
				(type solid)
			)
			(layer "F.SilkS")
		)
		(fp_line
			(start -4.875 -3.525)
			(end -4.875 -2.475)
			(stroke
				(width 0.2)
				(type solid)
			)
			(layer "F.SilkS")
		)
		(fp_circle
			(center -1.3 -4.375)
			(end -1.175 -4.375)
			(stroke
				(width 0.25)
				(type solid)
			)
			(fill no)
			(layer "F.SilkS")
		)
		(fp_line
			(start 4.875 -3.9)
			(end 4.875 3.675)
			(stroke
				(width 0.2)
				(type solid)
			)
			(layer "F.CrtYd")
		)
		(fp_line
			(start -4.875 -3.9)
			(end 4.875 -3.9)
			(stroke
				(width 0.2)
				(type solid)
			)
			(layer "F.CrtYd")
		)
		(fp_line
			(start -4.875 -3.9)
			(end -4.875 3.675)
			(stroke
				(width 0.2)
				(type solid)
			)
			(layer "F.CrtYd")
		)
		(fp_line
			(start -4.875 3.675)
			(end 4.875 3.675)
			(stroke
				(width 0.2)
				(type solid)
			)
			(layer "F.CrtYd")
		)
		(fp_line
			(start 4.875 -3.9)
			(end 4.875 3.675)
			(stroke
				(width 0.2)
				(type solid)
			)
			(layer "F.Fab")
		)
		(fp_line
			(start -4.875 -3.9)
			(end 4.875 -3.9)
			(stroke
				(width 0.2)
				(type solid)
			)
			(layer "F.Fab")
		)
		(fp_line
			(start -4.875 -3.9)
			(end -4.875 3.675)
			(stroke
				(width 0.2)
				(type solid)
			)
			(layer "F.Fab")
		)
		(fp_line
			(start 0 -0.5)
			(end 0 0.5)
			(stroke
				(width 0.1)
				(type solid)
			)
			(layer "F.Fab")
		)
		(fp_line
			(start -0.5 0)
			(end 0.5 0)
			(stroke
				(width 0.1)
				(type solid)
			)
			(layer "F.Fab")
		)
		(fp_line
			(start -4.875 3.675)
			(end 4.875 3.675)
			(stroke
				(width 0.2)
				(type solid)
			)
			(layer "F.Fab")
		)
		(fp_text user "${REFERENCE}"
			(at -0.00185 0.17175 90)
			(unlocked yes)
			(layer "F.Fab")
			(effects
				(font
					(face "Arial")
					(size 0.63 0.63)
					(thickness 0.1)
				)
				(justify left bottom)
			)
		)
		(pad "1" smd rect
			(at -1.3 -3.2 90)
			(size 0.45 1.2)
			(layers "F.Cu" "F.Mask" "F.Paste")
			(net "USB_VBUS")
			(solder_mask_margin 0)
			(solder_paste_margin 0)
		)
		(pad "2" smd rect
			(at -0.65 -3.2 90)
			(size 0.45 1.2)
			(layers "F.Cu" "F.Mask" "F.Paste")
			(net "FTDI_USB_R_N")
			(solder_mask_margin 0)
			(solder_paste_margin 0)
		)
		(pad "3" smd rect
			(at 0 -3.2 90)
			(size 0.45 1.2)
			(layers "F.Cu" "F.Mask" "F.Paste")
			(net "FTDI_USB_R_P")
			(solder_mask_margin 0)
			(solder_paste_margin 0)
		)
		(pad "4" smd rect
			(at 0.65 -3.2 90)
			(size 0.45 1.2)
			(layers "F.Cu" "F.Mask" "F.Paste")
			(solder_mask_margin 0)
			(solder_paste_margin 0)
		)
		(pad "5" smd rect
			(at 1.3 -3.2 90)
			(size 0.45 1.2)
			(layers "F.Cu" "F.Mask" "F.Paste")
			(net "GND")
			(solder_mask_margin 0)
			(solder_paste_margin 0)
		)
		(pad "6" thru_hole roundrect
			(at -3.6 -2.9 90)
			(size 1.2 1.6)
			(drill oval 0.6 1)
			(layers "*.Cu" "*.Mask")
			(remove_unused_layers no)
			(roundrect_rratio 0.5)
			(net "GND")
			(solder_mask_margin 0)
			(solder_paste_margin -1000)
		)
		(pad "7" thru_hole roundrect
			(at 3.6 -2.9 90)
			(size 1.2 1.6)
			(drill oval 0.6 1)
			(layers "*.Cu" "*.Mask")
			(remove_unused_layers no)
			(roundrect_rratio 0.5)
			(net "GND")
			(solder_mask_margin 0)
			(solder_paste_margin -1000)
		)
		(pad "8" thru_hole roundrect
			(at -4.225 -1.2 90)
			(size 1.1 1.8)
			(drill oval 0.5 1.2)
			(layers "*.Cu" "*.Mask")
			(remove_unused_layers no)
			(roundrect_rratio 0.5)
			(net "GND")
			(solder_mask_margin 0)
			(solder_paste_margin -1000)
		)
		(pad "8" smd roundrect
			(at -4.225 -0.325 90)
			(size 1.1 3.55)
			(layers "F.Cu" "F.Mask" "F.Paste")
			(roundrect_rratio 0.5)
			(net "GND")
			(solder_mask_margin 0)
			(solder_paste_margin -1000)
		)
		(pad "8" smd roundrect
			(at -4.225 -0.325 90)
			(size 1.1 3.55)
			(layers "B.Cu" "B.Mask" "B.Paste")
			(roundrect_rratio 0.5)
			(net "GND")
			(solder_mask_margin 0)
			(solder_paste_margin -1000)
		)
		(pad "8" thru_hole roundrect
			(at -4.225 0.55 90)
			(size 1.1 1.8)
			(drill oval 0.5 1.2)
			(layers "*.Cu" "*.Mask")
			(remove_unused_layers no)
			(roundrect_rratio 0.5)
			(net "GND")
			(solder_mask_margin 0)
			(solder_paste_margin -1000)
		)
		(pad "9" thru_hole roundrect
			(at 4.225 -1.2 90)
			(size 1.1 1.8)
			(drill oval 0.5 1.2)
			(layers "*.Cu" "*.Mask")
			(remove_unused_layers no)
			(roundrect_rratio 0.5)
			(net "GND")
			(solder_mask_margin 0)
			(solder_paste_margin -1000)
		)
		(pad "9" smd roundrect
			(at 4.225 -0.325 90)
			(size 1.1 3.55)
			(layers "F.Cu" "F.Mask" "F.Paste")
			(roundrect_rratio 0.5)
			(net "GND")
			(solder_mask_margin 0)
			(solder_paste_margin -1000)
		)
		(pad "9" smd roundrect
			(at 4.225 -0.325 90)
			(size 1.1 3.55)
			(layers "B.Cu" "B.Mask" "B.Paste")
			(roundrect_rratio 0.5)
			(net "GND")
			(solder_mask_margin 0)
			(solder_paste_margin -1000)
		)
		(pad "9" thru_hole roundrect
			(at 4.225 0.55 90)
			(size 1.1 1.8)
			(drill oval 0.5 1.2)
			(layers "*.Cu" "*.Mask")
			(remove_unused_layers no)
			(roundrect_rratio 0.5)
			(net "GND")
			(solder_mask_margin 0)
			(solder_paste_margin -1000)
		)
	)
	(footprint "SamacSys:155124M173200"
		(layer "F.Cu")
		(at 58.4511 141.8162 90)
		(property "Reference" "D18"
			(at -0.5714 1.701931 90)
			(unlocked yes)
			(layer "F.SilkS")
			(effects
				(font
					(size 0.762 0.762)
					(thickness 0.2286)
				)
			)
		)
		(property "Value" "155124M173200"
			(at 7.1471 2.605271 90)
			(unlocked yes)
			(layer "F.SilkS")
			(hide yes)
			(effects
				(font
					(size 0.762 0.762)
					(thickness 0.2286)
				)
			)
		)
		(sheetname "USER_IO_STATUS")
		(sheetfile "USER_IO_STATUS.kicad_sch")
		(duplicate_pad_numbers_are_jumpers no)
		(fp_line
			(start -0.8 0.5)
			(end 0.8 0.5)
			(stroke
				(width 0.1)
				(type solid)
			)
			(layer "F.SilkS")
		)
		(fp_arc
			(start -2 -0.1)
			(mid -1.95 -0.05)
			(end -2 0)
			(stroke
				(width 0.1)
				(type solid)
			)
			(layer "F.SilkS")
		)
		(fp_arc
			(start -2 0)
			(mid -2.05 -0.05)
			(end -2 -0.1)
			(stroke
				(width 0.1)
				(type solid)
			)
			(layer "F.SilkS")
		)
		(pad "1" smd rect
			(at -1.4 0 180)
			(size 0.9 0.6)
			(layers "F.Cu" "F.Mask" "F.Paste")
			(net "+3.3V")
		)
		(pad "2" smd rect
			(at -0.45 -0.325 90)
			(size 0.6 0.55)
			(layers "F.Cu" "F.Mask" "F.Paste")
			(net "NetD18_2")
		)
		(pad "3" smd rect
			(at 0.45 -0.325 90)
			(size 0.6 0.55)
			(layers "F.Cu" "F.Mask" "F.Paste")
			(net "NetD18_3")
		)
		(pad "4" smd rect
			(at 1.4 0 180)
			(size 0.9 0.6)
			(layers "F.Cu" "F.Mask" "F.Paste")
			(net "NetD18_4")
		)
	)
)
